(kicad_pcb
	(version 20260206)
	(generator "pcbnew")
	(generator_version "10.0")
	(general
		(thickness 1.6)
		(legacy_teardrops no)
	)
	(paper "A4")
	(title_block
		(title "Bryce Canyon_IOM_IOC_16318-2_OCP.brd")
		(comment 1 "Bryce Canyon / footprints 789-796 of 1605")
	)
	(layers
		(0 "F.Cu" signal "TOP")
		(4 "In1.Cu" signal "L2GND")
		(6 "In2.Cu" signal "L3")
		(8 "In3.Cu" signal "L4VCC")
		(10 "In4.Cu" signal "L5VCC")
		(12 "In5.Cu" signal "L6")
		(14 "In6.Cu" signal "L7GND")
		(2 "B.Cu" signal "BOTTOM")
		(9 "F.Adhes" user "F.Adhesive")
		(11 "B.Adhes" user "B.Adhesive")
		(13 "F.Paste" user "Package Geometry/Pastemask Top")
		(15 "B.Paste" user "Package Geometry/Pastemask Bottom")
		(5 "F.SilkS" user "Ref Des/Silkscreen Top")
		(7 "B.SilkS" user "Ref Des/Silkscreen Bottom")
		(1 "F.Mask" user "Board Geometry/Soldermask Top")
		(3 "B.Mask" user "Board Geometry/Soldermask Bottom")
		(17 "Dwgs.User" user "User.Drawings")
		(19 "Cmts.User" user "User.Comments")
		(21 "Eco1.User" user "User.Eco1")
		(23 "Eco2.User" user "User.Eco2")
		(25 "Edge.Cuts" user "Board Geometry/Outline")
		(27 "Margin" user)
		(31 "F.CrtYd" user "Package Geometry/Place Bound Top")
		(29 "B.CrtYd" user "Package Geometry/Place Bound Bottom")
		(35 "F.Fab" user "Ref Des/Assembly Top")
		(33 "B.Fab" user "Ref Des/Assembly Bottom")
	)
	(footprint ""
		(layer "F.Cu")
		(at 209.302096 -10.668 -90)
		(property "Reference" "R745"
			(at 0 0 270)
			(layer "F.SilkS")
			(hide yes)
			(effects
				(font
					(size 1.27 1.27)
				)
			)
		)
		(property "Value" "120R3F-L-GP"
			(at -0.0254 -2.5146 270)
			(unlocked yes)
			(layer "F.Fab")
			(hide yes)
			(effects
				(font
					(size 1.016 1.016)
					(thickness 0.1524)
				)
			)
		)
		(property "Device Type" "R603H22"
			(at -0.0254 -4.0386 270)
			(unlocked yes)
			(layer "F.Fab")
			(hide yes)
			(effects
				(font
					(size 1.016 1.016)
					(thickness 0.1524)
				)
			)
		)
		(duplicate_pad_numbers_are_jumpers no)
		(fp_line
			(start -0.4826 0)
			(end -0.2032 0)
			(stroke
				(width 0.2032)
				(type default)
			)
			(layer "F.SilkS")
		)
		(fp_line
			(start 0.2032 0)
			(end 0.4826 0)
			(stroke
				(width 0.2032)
				(type default)
			)
			(layer "F.SilkS")
		)
		(fp_rect
			(start -0.5842 1.3335)
			(end 0.5842 -1.3335)
			(stroke
				(width 0)
				(type default)
			)
			(fill no)
			(layer "F.CrtYd")
		)
		(fp_rect
			(start -0.5842 1.3335)
			(end 0.5842 -1.3335)
			(stroke
				(width 0)
				(type default)
			)
			(fill no)
			(layer "F.Fab")
		)
		(pad "1" smd custom
			(at 0 -0.762 270)
			(size 0.2159 0.2159)
			(layers "F.Cu" "F.Mask" "F.Paste")
			(net "ML_PWR_YELLOW_LED")
			(options
				(clearance outline)
				(anchor circle)
			)
			(primitives
				(gr_poly
					(pts
						(arc
							(start -0.3302 -0.4318)
							(mid -0.402042 -0.402042)
							(end -0.4318 -0.3302)
						)
						(arc
							(start -0.4318 0.3302)
							(mid -0.402042 0.402042)
							(end -0.3302 0.4318)
						)
						(arc
							(start 0.3302 0.4318)
							(mid 0.402042 0.402042)
							(end 0.4318 0.3302)
						)
						(arc
							(start 0.4318 -0.3302)
							(mid 0.402042 -0.402042)
							(end 0.3302 -0.4318)
						)
					)
					(width 0)
					(fill yes)
				)
			)
		)
		(pad "2" smd custom
			(at 0 0.762 270)
			(size 0.2159 0.2159)
			(layers "F.Cu" "F.Mask" "F.Paste")
			(net "ML_PWR_YELLOW_LED_R")
			(options
				(clearance outline)
				(anchor circle)
			)
			(primitives
				(gr_poly
					(pts
						(arc
							(start -0.3302 -0.4318)
							(mid -0.402042 -0.402042)
							(end -0.4318 -0.3302)
						)
						(arc
							(start -0.4318 0.3302)
							(mid -0.402042 0.402042)
							(end -0.3302 0.4318)
						)
						(arc
							(start 0.3302 0.4318)
							(mid 0.402042 0.402042)
							(end 0.4318 0.3302)
						)
						(arc
							(start 0.4318 -0.3302)
							(mid 0.402042 -0.402042)
							(end 0.3302 -0.4318)
						)
					)
					(width 0)
					(fill yes)
				)
			)
		)
	)
	(footprint ""
		(layer "F.Cu")
		(at 90.50782 -122.31878 90)
		(property "Reference" "R796"
			(at 0 0 90)
			(layer "F.SilkS")
			(hide yes)
			(effects
				(font
					(size 1.27 1.27)
				)
			)
		)
		(property "Value" "0R2J-2-GP"
			(at 0.064008 -3.993896 90)
			(unlocked yes)
			(layer "F.Fab")
			(hide yes)
			(effects
				(font
					(size 1.016 1.016)
					(thickness 0.1524)
				)
			)
		)
		(property "Device Type" "R402H16"
			(at 0.064008 -5.517896 90)
			(unlocked yes)
			(layer "F.Fab")
			(hide yes)
			(effects
				(font
					(size 1.016 1.016)
					(thickness 0.1524)
				)
			)
		)
		(duplicate_pad_numbers_are_jumpers no)
		(fp_line
			(start 0.508 -0.9398)
			(end -0.508 -0.9398)
			(stroke
				(width 0.1524)
				(type default)
			)
			(layer "F.SilkS")
		)
		(fp_line
			(start -0.508 -0.9398)
			(end -0.508 0.9398)
			(stroke
				(width 0.1524)
				(type default)
			)
			(layer "F.SilkS")
		)
		(fp_rect
			(start -0.508 0.9398)
			(end 0.508 -0.9398)
			(stroke
				(width 0)
				(type default)
			)
			(fill no)
			(layer "F.CrtYd")
		)
		(fp_rect
			(start -0.508 0.9398)
			(end 0.508 -0.9398)
			(stroke
				(width 0)
				(type default)
			)
			(fill no)
			(layer "F.Fab")
		)
		(pad "1" smd custom
			(at 0 -0.4445 90)
			(size 0.1397 0.1397)
			(layers "F.Cu" "F.Mask" "F.Paste")
			(net "UART_COMP_IN_RX")
			(options
				(clearance outline)
				(anchor circle)
			)
			(primitives
				(gr_poly
					(pts
						(arc
							(start -0.1778 -0.2794)
							(mid -0.249642 -0.249642)
							(end -0.2794 -0.1778)
						)
						(arc
							(start -0.2794 0.1778)
							(mid -0.249642 0.249642)
							(end -0.1778 0.2794)
						)
						(arc
							(start 0.1778 0.2794)
							(mid 0.249642 0.249642)
							(end 0.2794 0.1778)
						)
						(arc
							(start 0.2794 -0.1778)
							(mid 0.249642 -0.249642)
							(end 0.1778 -0.2794)
						)
					)
					(width 0)
					(fill yes)
				)
			)
		)
		(pad "2" smd custom
			(at 0 0.4445 90)
			(size 0.1397 0.1397)
			(layers "F.Cu" "F.Mask" "F.Paste")
			(net "UART_COMP_IN_R_RX")
			(options
				(clearance outline)
				(anchor circle)
			)
			(primitives
				(gr_poly
					(pts
						(arc
							(start -0.1778 -0.2794)
							(mid -0.249642 -0.249642)
							(end -0.2794 -0.1778)
						)
						(arc
							(start -0.2794 0.1778)
							(mid -0.249642 0.249642)
							(end -0.1778 0.2794)
						)
						(arc
							(start 0.1778 0.2794)
							(mid 0.249642 0.249642)
							(end 0.2794 0.1778)
						)
						(arc
							(start 0.2794 -0.1778)
							(mid 0.249642 -0.249642)
							(end 0.1778 -0.2794)
						)
					)
					(width 0)
					(fill yes)
				)
			)
		)
	)
	(footprint ""
		(layer "F.Cu")
		(at 205.1558 -121.2088 -90)
		(property "Reference" "C246"
			(at 0 0 270)
			(layer "F.SilkS")
			(hide yes)
			(effects
				(font
					(size 1.27 1.27)
				)
			)
		)
		(property "Value" "SC1KP50V2KX-1GP"
			(at 1.1811 -2.7051 270)
			(unlocked yes)
			(layer "F.Fab")
			(hide yes)
			(effects
				(font
					(size 1.016 1.016)
					(thickness 0.1524)
				)
			)
		)
		(property "Device Type" "C402H22"
			(at 1.1811 -4.2291 270)
			(unlocked yes)
			(layer "F.Fab")
			(hide yes)
			(effects
				(font
					(size 1.016 1.016)
					(thickness 0.1524)
				)
			)
		)
		(duplicate_pad_numbers_are_jumpers no)
		(fp_rect
			(start -0.4318 0.9525)
			(end 0.4318 -0.9525)
			(stroke
				(width 0)
				(type default)
			)
			(fill no)
			(layer "F.CrtYd")
		)
		(fp_rect
			(start -0.4318 0.9525)
			(end 0.4318 -0.9525)
			(stroke
				(width 0)
				(type default)
			)
			(fill no)
			(layer "F.Fab")
		)
		(pad "1" smd custom
			(at 0 -0.4445 270)
			(size 0.1524 0.1524)
			(layers "F.Cu" "F.Mask" "F.Paste")
			(net "P1V5_OUT")
			(options
				(clearance outline)
				(anchor circle)
			)
			(primitives
				(gr_poly
					(pts
						(arc
							(start 0.3048 -0.2032)
							(mid 0.275042 -0.275042)
							(end 0.2032 -0.3048)
						)
						(arc
							(start -0.2032 -0.3048)
							(mid -0.275042 -0.275042)
							(end -0.3048 -0.2032)
						)
						(arc
							(start -0.3048 0.2032)
							(mid -0.275042 0.275042)
							(end -0.2032 0.3048)
						)
						(arc
							(start 0.2032 0.3048)
							(mid 0.275042 0.275042)
							(end 0.3048 0.2032)
						)
					)
					(width 0)
					(fill yes)
				)
			)
		)
		(pad "2" smd custom
			(at 0 0.4445 270)
			(size 0.1524 0.1524)
			(layers "F.Cu" "F.Mask" "F.Paste")
			(net "TPS74801_P1V5_FB")
			(options
				(clearance outline)
				(anchor circle)
			)
			(primitives
				(gr_poly
					(pts
						(arc
							(start 0.3048 -0.2032)
							(mid 0.275042 -0.275042)
							(end 0.2032 -0.3048)
						)
						(arc
							(start -0.2032 -0.3048)
							(mid -0.275042 -0.275042)
							(end -0.3048 -0.2032)
						)
						(arc
							(start -0.3048 0.2032)
							(mid -0.275042 0.275042)
							(end -0.2032 0.3048)
						)
						(arc
							(start 0.2032 0.3048)
							(mid 0.275042 0.275042)
							(end 0.3048 0.2032)
						)
					)
					(width 0)
					(fill yes)
				)
			)
		)
	)
	(footprint ""
		(layer "F.Cu")
		(at 164.3634 -137.2362 90)
		(property "Reference" "C202"
			(at 0 0 90)
			(layer "F.SilkS")
			(hide yes)
			(effects
				(font
					(size 1.27 1.27)
				)
			)
		)
		(property "Value" "SC1U16V3KX-5GP"
			(at 0 -2.8194 90)
			(unlocked yes)
			(layer "F.Fab")
			(hide yes)
			(effects
				(font
					(size 1.016 1.016)
					(thickness 0.1524)
				)
			)
		)
		(property "Device Type" "C603H36"
			(at 0 -4.3434 90)
			(unlocked yes)
			(layer "F.Fab")
			(hide yes)
			(effects
				(font
					(size 1.016 1.016)
					(thickness 0.1524)
				)
			)
		)
		(duplicate_pad_numbers_are_jumpers no)
		(fp_line
			(start 0.508 0)
			(end -0.508 0)
			(stroke
				(width 0.2032)
				(type default)
			)
			(layer "F.SilkS")
		)
		(fp_rect
			(start -0.5842 1.3335)
			(end 0.5842 -1.3335)
			(stroke
				(width 0)
				(type default)
			)
			(fill no)
			(layer "F.CrtYd")
		)
		(fp_rect
			(start -0.5842 1.3335)
			(end 0.5842 -1.3335)
			(stroke
				(width 0)
				(type default)
			)
			(fill no)
			(layer "F.Fab")
		)
		(pad "1" smd custom
			(at 0 -0.762 90)
			(size 0.2159 0.2159)
			(layers "F.Cu" "F.Mask" "F.Paste")
			(net "P12V_STBY_VCC_PU4")
			(options
				(clearance outline)
				(anchor circle)
			)
			(primitives
				(gr_poly
					(pts
						(arc
							(start -0.3302 -0.4318)
							(mid -0.402042 -0.402042)
							(end -0.4318 -0.3302)
						)
						(arc
							(start -0.4318 0.3302)
							(mid -0.402042 0.402042)
							(end -0.3302 0.4318)
						)
						(arc
							(start 0.3302 0.4318)
							(mid 0.402042 0.402042)
							(end 0.4318 0.3302)
						)
						(arc
							(start 0.4318 -0.3302)
							(mid 0.402042 -0.402042)
							(end 0.3302 -0.4318)
						)
					)
					(width 0)
					(fill yes)
				)
			)
		)
		(pad "2" smd custom
			(at 0 0.762 90)
			(size 0.2159 0.2159)
			(layers "F.Cu" "F.Mask" "F.Paste")
			(net "GND")
			(options
				(clearance outline)
				(anchor circle)
			)
			(primitives
				(gr_poly
					(pts
						(arc
							(start -0.3302 -0.4318)
							(mid -0.402042 -0.402042)
							(end -0.4318 -0.3302)
						)
						(arc
							(start -0.4318 0.3302)
							(mid -0.402042 0.402042)
							(end -0.3302 0.4318)
						)
						(arc
							(start 0.3302 0.4318)
							(mid 0.402042 0.402042)
							(end 0.4318 0.3302)
						)
						(arc
							(start 0.4318 -0.3302)
							(mid 0.402042 -0.402042)
							(end 0.3302 -0.4318)
						)
					)
					(width 0)
					(fill yes)
				)
			)
		)
	)
	(footprint ""
		(layer "F.Cu")
		(at 84.87791 -137.060686 -90)
		(property "Reference" "R105"
			(at 0 0 270)
			(layer "F.SilkS")
			(hide yes)
			(effects
				(font
					(size 1.27 1.27)
				)
			)
		)
		(property "Value" "4K7R2F-GP"
			(at 0.064008 -3.993896 270)
			(unlocked yes)
			(layer "F.Fab")
			(hide yes)
			(effects
				(font
					(size 1.016 1.016)
					(thickness 0.1524)
				)
			)
		)
		(property "Device Type" "R402H16"
			(at 0.064008 -5.517896 270)
			(unlocked yes)
			(layer "F.Fab")
			(hide yes)
			(effects
				(font
					(size 1.016 1.016)
					(thickness 0.1524)
				)
			)
		)
		(duplicate_pad_numbers_are_jumpers no)
		(fp_line
			(start -0.508 -0.9398)
			(end -0.508 0.9398)
			(stroke
				(width 0.1524)
				(type default)
			)
			(layer "F.SilkS")
		)
		(fp_line
			(start 0.508 -0.9398)
			(end -0.508 -0.9398)
			(stroke
				(width 0.1524)
				(type default)
			)
			(layer "F.SilkS")
		)
		(fp_rect
			(start -0.508 0.9398)
			(end 0.508 -0.9398)
			(stroke
				(width 0)
				(type default)
			)
			(fill no)
			(layer "F.CrtYd")
		)
		(fp_rect
			(start -0.508 0.9398)
			(end 0.508 -0.9398)
			(stroke
				(width 0)
				(type default)
			)
			(fill no)
			(layer "F.Fab")
		)
		(pad "1" smd custom
			(at 0 -0.4445 270)
			(size 0.1397 0.1397)
			(layers "F.Cu" "F.Mask" "F.Paste")
			(net "P3V3_STBY")
			(options
				(clearance outline)
				(anchor circle)
			)
			(primitives
				(gr_poly
					(pts
						(arc
							(start -0.1778 -0.2794)
							(mid -0.249642 -0.249642)
							(end -0.2794 -0.1778)
						)
						(arc
							(start -0.2794 0.1778)
							(mid -0.249642 0.249642)
							(end -0.1778 0.2794)
						)
						(arc
							(start 0.1778 0.2794)
							(mid 0.249642 0.249642)
							(end 0.2794 0.1778)
						)
						(arc
							(start 0.2794 -0.1778)
							(mid 0.249642 -0.249642)
							(end 0.1778 -0.2794)
						)
					)
					(width 0)
					(fill yes)
				)
			)
		)
		(pad "2" smd custom
			(at 0 0.4445 270)
			(size 0.1397 0.1397)
			(layers "F.Cu" "F.Mask" "F.Paste")
			(net "D_FLIP_CLR#")
			(options
				(clearance outline)
				(anchor circle)
			)
			(primitives
				(gr_poly
					(pts
						(arc
							(start -0.1778 -0.2794)
							(mid -0.249642 -0.249642)
							(end -0.2794 -0.1778)
						)
						(arc
							(start -0.2794 0.1778)
							(mid -0.249642 0.249642)
							(end -0.1778 0.2794)
						)
						(arc
							(start 0.1778 0.2794)
							(mid 0.249642 0.249642)
							(end 0.2794 0.1778)
						)
						(arc
							(start 0.2794 -0.1778)
							(mid 0.249642 -0.249642)
							(end 0.1778 -0.2794)
						)
					)
					(width 0)
					(fill yes)
				)
			)
		)
	)
	(footprint ""
		(layer "F.Cu")
		(at 49.09439 -158.1912)
		(property "Reference" "R168"
			(at 0 0 0)
			(layer "F.SilkS")
			(hide yes)
			(effects
				(font
					(size 1.27 1.27)
				)
			)
		)
		(property "Value" "0R2J-2-GP"
			(at 0.064008 -3.993896 0)
			(unlocked yes)
			(layer "F.Fab")
			(hide yes)
			(effects
				(font
					(size 1.016 1.016)
					(thickness 0.1524)
				)
			)
		)
		(property "Device Type" "R402H16"
			(at 0.064008 -5.517896 0)
			(unlocked yes)
			(layer "F.Fab")
			(hide yes)
			(effects
				(font
					(size 1.016 1.016)
					(thickness 0.1524)
				)
			)
		)
		(duplicate_pad_numbers_are_jumpers no)
		(fp_line
			(start -0.508 -0.9398)
			(end -0.508 0.9398)
			(stroke
				(width 0.1524)
				(type default)
			)
			(layer "F.SilkS")
		)
		(fp_line
			(start 0.508 -0.9398)
			(end -0.508 -0.9398)
			(stroke
				(width 0.1524)
				(type default)
			)
			(layer "F.SilkS")
		)
		(fp_rect
			(start -0.508 0.9398)
			(end 0.508 -0.9398)
			(stroke
				(width 0)
				(type default)
			)
			(fill no)
			(layer "F.CrtYd")
		)
		(fp_rect
			(start -0.508 0.9398)
			(end 0.508 -0.9398)
			(stroke
				(width 0)
				(type default)
			)
			(fill no)
			(layer "F.Fab")
		)
		(pad "1" smd custom
			(at 0 -0.4445)
			(size 0.1397 0.1397)
			(layers "F.Cu" "F.Mask" "F.Paste")
			(net "I2C_DPB_MISC_SCL_OUT")
			(options
				(clearance outline)
				(anchor circle)
			)
			(primitives
				(gr_poly
					(pts
						(arc
							(start -0.1778 -0.2794)
							(mid -0.249642 -0.249642)
							(end -0.2794 -0.1778)
						)
						(arc
							(start -0.2794 0.1778)
							(mid -0.249642 0.249642)
							(end -0.1778 0.2794)
						)
						(arc
							(start 0.1778 0.2794)
							(mid 0.249642 0.249642)
							(end 0.2794 0.1778)
						)
						(arc
							(start 0.2794 -0.1778)
							(mid 0.249642 -0.249642)
							(end 0.1778 -0.2794)
						)
					)
					(width 0)
					(fill yes)
				)
			)
		)
		(pad "2" smd custom
			(at 0 0.4445)
			(size 0.1397 0.1397)
			(layers "F.Cu" "F.Mask" "F.Paste")
			(net "BMC_SMB6_CLK")
			(options
				(clearance outline)
				(anchor circle)
			)
			(primitives
				(gr_poly
					(pts
						(arc
							(start -0.1778 -0.2794)
							(mid -0.249642 -0.249642)
							(end -0.2794 -0.1778)
						)
						(arc
							(start -0.2794 0.1778)
							(mid -0.249642 0.249642)
							(end -0.1778 0.2794)
						)
						(arc
							(start 0.1778 0.2794)
							(mid 0.249642 0.249642)
							(end 0.2794 0.1778)
						)
						(arc
							(start 0.2794 -0.1778)
							(mid 0.249642 -0.249642)
							(end 0.1778 -0.2794)
						)
					)
					(width 0)
					(fill yes)
				)
			)
		)
	)
	(footprint ""
		(layer "F.Cu")
		(at 203.3524 -48.2854 180)
		(property "Reference" "R631"
			(at 0 0 180)
			(layer "F.SilkS")
			(hide yes)
			(effects
				(font
					(size 1.27 1.27)
				)
			)
		)
		(property "Value" "4K7R2F-GP"
			(at 0.064008 -3.993896 180)
			(unlocked yes)
			(layer "F.Fab")
			(hide yes)
			(effects
				(font
					(size 1.016 1.016)
					(thickness 0.1524)
				)
			)
		)
		(property "Device Type" "R402H16"
			(at 0.064008 -5.517896 180)
			(unlocked yes)
			(layer "F.Fab")
			(hide yes)
			(effects
				(font
					(size 1.016 1.016)
					(thickness 0.1524)
				)
			)
		)
		(duplicate_pad_numbers_are_jumpers no)
		(fp_line
			(start 0.508 -0.9398)
			(end -0.508 -0.9398)
			(stroke
				(width 0.1524)
				(type default)
			)
			(layer "F.SilkS")
		)
		(fp_line
			(start -0.508 -0.9398)
			(end -0.508 0.9398)
			(stroke
				(width 0.1524)
				(type default)
			)
			(layer "F.SilkS")
		)
		(fp_rect
			(start -0.508 0.9398)
			(end 0.508 -0.9398)
			(stroke
				(width 0)
				(type default)
			)
			(fill no)
			(layer "F.CrtYd")
		)
		(fp_rect
			(start -0.508 0.9398)
			(end 0.508 -0.9398)
			(stroke
				(width 0)
				(type default)
			)
			(fill no)
			(layer "F.Fab")
		)
		(pad "1" smd custom
			(at 0 -0.4445 180)
			(size 0.1397 0.1397)
			(layers "F.Cu" "F.Mask" "F.Paste")
			(net "P1V8")
			(options
				(clearance outline)
				(anchor circle)
			)
			(primitives
				(gr_poly
					(pts
						(arc
							(start -0.1778 -0.2794)
							(mid -0.249642 -0.249642)
							(end -0.2794 -0.1778)
						)
						(arc
							(start -0.2794 0.1778)
							(mid -0.249642 0.249642)
							(end -0.1778 0.2794)
						)
						(arc
							(start 0.1778 0.2794)
							(mid 0.249642 0.249642)
							(end 0.2794 0.1778)
						)
						(arc
							(start 0.2794 -0.1778)
							(mid 0.249642 -0.249642)
							(end 0.1778 -0.2794)
						)
					)
					(width 0)
					(fill yes)
				)
			)
		)
		(pad "2" smd custom
			(at 0 0.4445 180)
			(size 0.1397 0.1397)
			(layers "F.Cu" "F.Mask" "F.Paste")
			(net "ICE1_TMS")
			(options
				(clearance outline)
				(anchor circle)
			)
			(primitives
				(gr_poly
					(pts
						(arc
							(start -0.1778 -0.2794)
							(mid -0.249642 -0.249642)
							(end -0.2794 -0.1778)
						)
						(arc
							(start -0.2794 0.1778)
							(mid -0.249642 0.249642)
							(end -0.1778 0.2794)
						)
						(arc
							(start 0.1778 0.2794)
							(mid 0.249642 0.249642)
							(end 0.2794 0.1778)
						)
						(arc
							(start 0.2794 -0.1778)
							(mid 0.249642 -0.249642)
							(end 0.1778 -0.2794)
						)
					)
					(width 0)
					(fill yes)
				)
			)
		)
	)
	(footprint ""
		(layer "F.Cu")
		(at 84.438744 -160.351216 180)
		(property "Reference" "C237"
			(at 0 0 180)
			(layer "F.SilkS")
			(hide yes)
			(effects
				(font
					(size 1.27 1.27)
				)
			)
		)
		(property "Value" "SC10U6D3V5KX-4GP"
			(at -0.0762 -6.1214 180)
			(unlocked yes)
			(layer "F.Fab")
			(hide yes)
			(effects
				(font
					(size 1.016 1.016)
					(thickness 0.1524)
				)
			)
		)
		(property "Device Type" "C805H58"
			(at -0.0762 -8.1534 180)
			(unlocked yes)
			(layer "F.Fab")
			(hide yes)
			(effects
				(font
					(size 1.016 1.016)
					(thickness 0.1524)
				)
			)
		)
		(duplicate_pad_numbers_are_jumpers no)
		(fp_line
			(start 0.635 0)
			(end -0.635 0)
			(stroke
				(width 0.508)
				(type default)
			)
			(layer "F.SilkS")
		)
		(fp_rect
			(start -0.9652 1.778)
			(end 0.9652 -1.778)
			(stroke
				(width 0)
				(type default)
			)
			(fill no)
			(layer "F.CrtYd")
		)
		(fp_poly
			(pts
				(xy -0.9652 -1.778) (xy 0.9652 -1.778) (xy 0.9652 1.778) (xy -0.9652 1.778)
			)
			(stroke
				(width 0)
				(type default)
			)
			(fill no)
			(layer "F.Fab")
		)
		(pad "1" smd rect
			(at 0 -0.9652 180)
			(size 1.397 1.143)
			(layers "F.Cu" "F.Mask" "F.Paste")
			(net "TPS74801_P1V15_STBY_OUT")
		)
		(pad "2" smd rect
			(at 0 0.9652 180)
			(size 1.397 1.143)
			(layers "F.Cu" "F.Mask" "F.Paste")
			(net "GND")
		)
	)
)
